FILE_TYPE = CONNECTIVITY;
{Allegro Design Entry HDL 16.6-p007 (v16-6-112F) 10/10/2012}
"PAGE_NUMBER" = 184;
0"NC";
1"GND\g";
2"GND\g";
3"P3V3_STBY\g";
4"SMB_SENSOR_STBY_LVC3_SCL";
5"IRQ_PIRQA_SPI_TPM_N";
6"FM_TPM_PRES_RST_N";
7"SMB_SENSOR_STBY_LVC3_SDA";
8"RST_PLTRST_BUF_N";
9"SPI_PCH_TPM_CS_R_N";
10"SPI_PCH_TPM_MOSI_R";
11"SPI_PCH_MISO";
12"SPI_PCH_MOSI";
13"SPI_PCH_TPM_CLK_R";
14"SPI_PCH_CLK";
15"SPI_PCH_TPM_CS_N";
16"IRQ_SPI_TPM_N_R";
17"SPI_PCH_TPM_MISO_R";
%"GND"
"1","(-3225,-3900)","2","mstr_symbols","I101";
;
VOLTAGE"0"
BOM_COST"MEM"
SIZE"1B"
CDS_LIB"mstr_symbols"
ROOM"DDR4_CH_G"
BODY_TYPE"PLUMBING"
HDL_POWER"GND";
"A\NAC"1;
%"STANDOFF"
"2","(-5125,-1900)","0","mstr_misc","I104";
;
CDS_SEC"1"
PART_NUMBER"H72821-001"
MATERIAL"SO"
LOCATION"RM8D1"
PACK_TYPE"TH1"
CDS_LOCATION"RM8D1"
SEC"1"
SEC_TYPE"TH1"
CDS_LIB"mstr_misc";
"IO1"
$PN"1"2;
%"GND"
"1","(-4850,-2125)","0","mstr_symbols","I105";
;
VOLTAGE"0.0V"
SIZE"1B"
CDS_LIB"mstr_symbols"
BODY_TYPE"PLUMBING"
HDL_POWER"GND";
"A\NAC"2;
%"SCONN11_H67026001"
"1","(-3700,-3375)","0","mstr_sconn","I87";
;
CDS_SEC"1"
LOCATION"J8E1"
PART_NUMBER"H67026-001"
MATERIAL"CONN"
PACK_TYPE"SM"
CDS_LOCATION"J8E1"
SEC"1"
SEC_TYPE"SM"
CDS_LIB"mstr_sconn"
CDS_LMAN_SYM_OUTLINE"-300,450,300,-450"
BOM_COST"MIO_SECURITY"
ROOM"TPM";
"IO7"
$PN"7"3;
"IO8"
$PN"8"6;
"IO5"
$PN"5"9;
"IO6"
$PN"6"7;
"IO4"
$PN"4"17;
"IO3"
$PN"3"10;
"IO2"
$PN"2"8;
"IO1"
$PN"1"13;
"MP1"
$PN"MP1"1;
"IO9"
$PN"9"16;
"IO10"
$PN"10"4;
"IO11"
$PN"11"1;
"MP2"
$PN"MP2"1;
%"RES"
"1","(-4750,-3175)","0","mstr_discrete","I88";
;
CDS_SEC"1"
VALUE"33.2"
PACK_TYPE"0402"
WATTAGE"1/16W"
MATERIAL"CHIP"
PART_NUMBER"G21796-074"
TOLERANCE"1%"
LOCATION"R8E9"
CDS_LOCATION"R8E9"
SEC"1"
BOM_COST"MIO_SECURITY"
CDS_LIB"mstr_discrete"
SEC_TYPE"0402"
ROOM"TPM";
"B"
$PN"2"13;
"A"
$PN"1"14;
%"RES"
"1","(-4750,-3575)","0","mstr_discrete","I92";
;
CDS_SEC"1"
PACK_TYPE"0402"
MATERIAL"CHIP"
LOCATION"R8D35"
PART_NUMBER"G21497-005"
WATTAGE"1/16W"
TOLERANCE"5%"
VALUE"0.0"
CDS_LOCATION"R8D35"
SEC"1"
SEC_TYPE"0402"
CDS_LIB"mstr_discrete"
BOM_COST"MIO_SECURITY"
ROOM"TPM";
"B"
$PN"2"9;
"A"
$PN"1"15;
%"RES"
"1","(-4725,-3475)","0","mstr_discrete","I93";
;
CDS_SEC"1"
PACK_TYPE"0402"
MATERIAL"CHIP"
PART_NUMBER"G21796-074"
WATTAGE"1/16W"
LOCATION"R8E13"
TOLERANCE"1%"
VALUE"33.2"
CDS_LOCATION"R8E13"
SEC"1"
CDS_LIB"mstr_discrete"
BOM_COST"MIO_SECURITY"
SEC_TYPE"0402"
ROOM"TPM";
"B"
$PN"2"17;
"A"
$PN"1"11;
%"RES"
"1","(-4725,-3375)","0","mstr_discrete","I95";
;
CDS_SEC"1"
PACK_TYPE"0402"
PART_NUMBER"G21796-074"
VALUE"33.2"
WATTAGE"1/16W"
MATERIAL"CHIP"
TOLERANCE"1%"
LOCATION"R8E10"
CDS_LOCATION"R8E10"
SEC"1"
BOM_COST"MIO_SECURITY"
CDS_LIB"mstr_discrete"
SEC_TYPE"0402"
ROOM"TPM";
"B"
$PN"2"10;
"A"
$PN"1"12;
%"P3V3_STBY"
"1","(-3050,-2900)","0","mstr_symbols","I97";
;
VOLTAGE"3.3V"
SIZE"1B"
CDS_LIB"mstr_symbols"
BODY_TYPE"PLUMBING"
HDL_POWER"P3V3_STBY";
"G\NAC"3;
%"RES"
"1","(-2575,-3425)","0","mstr_discrete","I99";
;
LOCATION"R8E1"
TOLERANCE"5%"
WATTAGE"1/16W"
PACK_TYPE"0402"
VALUE"0.0"
PART_NUMBER"G21497-005"
MATERIAL"CHIP"
CDS_LOCATION"R8E1"
$SEC"1"
CDS_SEC"1"
BOM_COST"MIO_SECURITY"
CDS_LIB"mstr_discrete"
ROOM"TPM";
"B"
$PN"2"5;
"A"
$PN"1"16;
END.
